FILE_TYPE = MACRO_DRAWING;
SET COLOR_WIRE YELLOW;
SET COLOR_PROP MONO;
SET COLOR_DOT WHITE;
SET COLOR_ARC YELLOW;
SET COLOR_BODY GREEN;
SET COLOR_NOTE MONO;
SET PROP_DISPLAY VALUE;
SET PAGE_NUMBER P172;
FORCEADD OFFPAGE..2
(2125 2100);
FORCEPROP 2 LAST $XR0 116 
J 0
(2314 2100);
DISPLAY 0.638298 (2314 2100);
PAINT MONO (2314 2100);
FORCEPROP 2 LAST CDS_LIB mstr_standard
J 0
(2125 2100);
DISPLAY 1.382979 (2125 2100);
PAINT ORANGE (2125 2100);
DISPLAY INVISIBLE (2125 2100);
FORCEPROP 2 LAST PATH I10
J 0
(2325 2150);
DISPLAY 1.021277 (2325 2150);
PAINT ORANGE (2325 2150);
DISPLAY INVISIBLE (2325 2150);
FORCEPROP 2 LAST ROOM ST_SATA
J 0
(2325 2150);
DISPLAY 1.404255 (2325 2150);
PAINT ORANGE (2325 2150);
DISPLAY INVISIBLE (2325 2150);
FORCEPROP 1 LAST OFFPAGE TRUE
J 0
(2450 1975);
PAINT GREEN (2450 1975);
DISPLAY INVISIBLE (2450 1975);
FORCEPROP 1 LAST COMMENT_BODY TRUE
J 0
(2080 2005);
DISPLAY 1.170213 (2080 2005);
PAINT GREEN (2080 2005);
DISPLAY INVISIBLE (2080 2005);
FORCEADD OFFPAGE..4
(2125 2300);
FORCEPROP 2 LAST $XR0 116 
J 0
(2311 2300);
DISPLAY 0.638298 (2311 2300);
PAINT MONO (2311 2300);
FORCEPROP 2 LAST ROOM ST_SATA
J 0
(2325 2350);
DISPLAY 1.404255 (2325 2350);
PAINT ORANGE (2325 2350);
DISPLAY INVISIBLE (2325 2350);
FORCEPROP 2 LAST PATH I11
J 0
(2325 2350);
DISPLAY 1.021277 (2325 2350);
PAINT ORANGE (2325 2350);
DISPLAY INVISIBLE (2325 2350);
FORCEPROP 2 LAST CDS_LIB mstr_standard
J 0
(2125 2300);
DISPLAY 1.382979 (2125 2300);
PAINT ORANGE (2125 2300);
DISPLAY INVISIBLE (2125 2300);
FORCEPROP 1 LAST OFFPAGE TRUE
J 0
(2450 2175);
PAINT GREEN (2450 2175);
DISPLAY INVISIBLE (2450 2175);
FORCEPROP 1 LAST COMMENT_BODY TRUE
J 0
(2100 2200);
DISPLAY 1.170213 (2100 2200);
PAINT GREEN (2100 2200);
DISPLAY INVISIBLE (2100 2200);
FORCEADD OFFPAGE..4
(2125 2250);
FORCEPROP 2 LAST $XR0 116 
J 0
(2311 2250);
DISPLAY 0.638298 (2311 2250);
PAINT MONO (2311 2250);
FORCEPROP 2 LAST ROOM ST_SATA
J 0
(2325 2300);
DISPLAY 1.404255 (2325 2300);
PAINT ORANGE (2325 2300);
DISPLAY INVISIBLE (2325 2300);
FORCEPROP 2 LAST PATH I12
J 0
(2325 2300);
DISPLAY 1.021277 (2325 2300);
PAINT ORANGE (2325 2300);
DISPLAY INVISIBLE (2325 2300);
FORCEPROP 2 LAST CDS_LIB mstr_standard
J 0
(2125 2250);
DISPLAY 1.382979 (2125 2250);
PAINT ORANGE (2125 2250);
DISPLAY INVISIBLE (2125 2250);
FORCEPROP 1 LAST OFFPAGE TRUE
J 0
(2450 2125);
PAINT GREEN (2450 2125);
DISPLAY INVISIBLE (2450 2125);
FORCEPROP 1 LAST COMMENT_BODY TRUE
J 0
(2100 2150);
DISPLAY 1.170213 (2100 2150);
PAINT GREEN (2100 2150);
DISPLAY INVISIBLE (2100 2150);
FORCEADD GND..1
(-650 50);
FORCEPROP 3 LASTPIN (-650 100) SIG_NAME GND\g
J 0
(-640 110);
DISPLAY 0.659574 (-640 110);
PAINT MONO (-640 110);
DISPLAY INVISIBLE (-640 110);
FORCEPROP 1 LAST VOLTAGE 0
J 0
(-650 50);
PAINT SKYBLUE (-650 50);
DISPLAY INVISIBLE (-650 50);
FORCEPROP 2 LAST CDS_LIB mstr_symbols
J 0
(-650 50);
PAINT ORANGE (-650 50);
DISPLAY INVISIBLE (-650 50);
FORCEPROP 1 LAST PATH I35
J 0
(-575 50);
DISPLAY 0.872340 (-575 50);
PAINT AQUA (-575 50);
DISPLAY INVISIBLE (-575 50);
FORCEPROP 1 LAST SIZE 1B
J 0
(-575 0);
DISPLAY 0.617021 (-575 0);
PAINT ORANGE (-575 0);
DISPLAY INVISIBLE (-575 0);
FORCEPROP 2 LAST ROOM ST_SATA
J 0
(-825 125);
DISPLAY 0.617021 (-825 125);
PAINT ORANGE (-825 125);
DISPLAY INVISIBLE (-825 125);
FORCEPROP 1 LAST BODY_TYPE PLUMBING
J 0
(-695 7);
DISPLAY 0.340426 (-695 7);
PAINT GREEN (-695 7);
DISPLAY INVISIBLE (-695 7);
FORCEPROP 1 LAST HDL_POWER GND
J 0
(-650 200);
DISPLAY 0.617021 (-650 200);
PAINT GREEN (-650 200);
DISPLAY INVISIBLE (-650 200);
FORCEADD CAP..1
(-650 250);
FORCEPROP 1 LAST LOCATION C9B2
J 0
(-600 350);
DISPLAY 0.617021 (-600 350);
PAINT AQUA (-600 350);
FORCEPROP 1 LAST TOLERANCE 10%
J 0
(-600 200);
DISPLAY 0.617021 (-600 200);
PAINT SKYBLUE (-600 200);
FORCEPROP 1 LAST PACK_TYPE 0805
J 0
(-600 50);
DISPLAY 0.617021 (-600 50);
PAINT SKYBLUE (-600 50);
FORCEPROP 1 LAST MATERIAL X6S
J 0
(-600 150);
DISPLAY 0.617021 (-600 150);
PAINT SKYBLUE (-600 150);
FORCEPROP 1 LASTPIN (-650 150) $PN 2
J 0
(-640 130);
DISPLAY 0.617021 (-640 130);
PAINT ORANGE (-640 130);
FORCEPROP 1 LAST PART_NUMBER C95333-007
J 0
(-600 100);
DISPLAY 0.617021 (-600 100);
PAINT BLUE (-600 100);
FORCEPROP 1 LAST VOLTAGE 16V
J 0
(-600 250);
DISPLAY 0.617021 (-600 250);
PAINT SKYBLUE (-600 250);
FORCEPROP 1 LASTPIN (-650 350) $PN 1
J 0
(-640 330);
DISPLAY 0.617021 (-640 330);
PAINT ORANGE (-640 330);
FORCEPROP 1 LAST VALUE 10UF
J 0
(-600 300);
DISPLAY 0.617021 (-600 300);
PAINT SKYBLUE (-600 300);
FORCEPROP 2 LAST SEC_TYPE 0805
J 0
(-600 450);
DISPLAY 1.021277 (-600 450);
PAINT ORANGE (-600 450);
DISPLAY INVISIBLE (-600 450);
FORCEPROP 2 LAST SEC 1
J 0
(-600 450);
PAINT MONO (-600 450);
DISPLAY INVISIBLE (-600 450);
FORCEPROP 2 LAST CDS_LIB mstr_discrete
J 0
(-650 250);
PAINT ORANGE (-650 250);
DISPLAY INVISIBLE (-650 250);
FORCEPROP 2 LAST CDS_LOCATION C9B2
J 0
(-600 350);
DISPLAY 0.617021 (-600 350);
PAINT AQUA (-600 350);
DISPLAY INVISIBLE (-600 350);
FORCEPROP 1 LAST PATH I36
J 0
(-600 400);
DISPLAY 0.978723 (-600 400);
PAINT WHITE (-600 400);
DISPLAY INVISIBLE (-600 400);
FORCEPROP 2 LAST ROOM ST_SATA
J 0
(-600 400);
DISPLAY 1.361702 (-600 400);
PAINT ORANGE (-600 400);
DISPLAY INVISIBLE (-600 400);
FORCEADD P12V..1
(1375 550);
FORCEPROP 3 LASTPIN (1375 500) SIG_NAME P12V\g
J 0
(1385 510);
DISPLAY 0.659574 (1385 510);
PAINT MONO (1385 510);
DISPLAY INVISIBLE (1385 510);
FORCEPROP 1 LAST SIZE 1B
J 0
(1420 572);
DISPLAY 0.340426 (1420 572);
PAINT GREEN (1420 572);
DISPLAY INVISIBLE (1420 572);
FORCEPROP 2 LAST CDS_LIB mstr_symbols
J 0
(1375 550);
PAINT ORANGE (1375 550);
DISPLAY INVISIBLE (1375 550);
FORCEPROP 1 LAST PATH I37
J 0
(1420 552);
DISPLAY 0.340426 (1420 552);
PAINT GREEN (1420 552);
DISPLAY INVISIBLE (1420 552);
FORCEPROP 1 LAST VOLTAGE 12.0V
J 0
(1330 507);
DISPLAY 0.340426 (1330 507);
PAINT SKYBLUE (1330 507);
DISPLAY INVISIBLE (1330 507);
FORCEPROP 1 LAST BODY_TYPE PLUMBING
J 0
(1330 507);
DISPLAY 0.340426 (1330 507);
PAINT GREEN (1330 507);
DISPLAY INVISIBLE (1330 507);
FORCEPROP 1 LAST HDL_POWER P12V
J 0
(1175 400);
DISPLAY 0.872340 (1175 400);
PAINT ORANGE (1175 400);
DISPLAY INVISIBLE (1175 400);
FORCEADD CAP..1
(-1050 250);
FORCEPROP 1 LAST PACK_TYPE 0805
J 0
(-1000 50);
DISPLAY 0.617021 (-1000 50);
PAINT SKYBLUE (-1000 50);
FORCEPROP 1 LAST PART_NUMBER C95333-007
J 0
(-1000 100);
DISPLAY 0.617021 (-1000 100);
PAINT BLUE (-1000 100);
FORCEPROP 1 LASTPIN (-1050 150) $PN 2
J 0
(-1040 130);
DISPLAY 0.617021 (-1040 130);
PAINT ORANGE (-1040 130);
FORCEPROP 1 LAST MATERIAL X6S
J 0
(-1000 150);
DISPLAY 0.617021 (-1000 150);
PAINT SKYBLUE (-1000 150);
FORCEPROP 1 LASTPIN (-1050 350) $PN 1
J 0
(-1040 330);
DISPLAY 0.617021 (-1040 330);
PAINT ORANGE (-1040 330);
FORCEPROP 1 LAST TOLERANCE 10%
J 0
(-1000 200);
DISPLAY 0.617021 (-1000 200);
PAINT SKYBLUE (-1000 200);
FORCEPROP 1 LAST VOLTAGE 16V
J 0
(-1000 250);
DISPLAY 0.617021 (-1000 250);
PAINT SKYBLUE (-1000 250);
FORCEPROP 1 LAST VALUE 10UF
J 0
(-1000 300);
DISPLAY 0.617021 (-1000 300);
PAINT SKYBLUE (-1000 300);
FORCEPROP 1 LAST LOCATION C9B1
J 0
(-1000 350);
DISPLAY 0.617021 (-1000 350);
PAINT AQUA (-1000 350);
FORCEPROP 2 LAST CDS_LOCATION C9B1
J 0
(-1000 350);
DISPLAY 0.617021 (-1000 350);
PAINT AQUA (-1000 350);
DISPLAY INVISIBLE (-1000 350);
FORCEPROP 2 LAST CDS_LIB mstr_discrete
J 0
(-1050 250);
PAINT ORANGE (-1050 250);
DISPLAY INVISIBLE (-1050 250);
FORCEPROP 1 LAST PATH I39
J 0
(-1000 400);
DISPLAY 0.978723 (-1000 400);
PAINT WHITE (-1000 400);
DISPLAY INVISIBLE (-1000 400);
FORCEPROP 2 LAST ROOM ST_SATA
J 0
(-1000 400);
DISPLAY 1.361702 (-1000 400);
PAINT ORANGE (-1000 400);
DISPLAY INVISIBLE (-1000 400);
FORCEPROP 2 LAST SEC_TYPE 0805
J 0
(-1000 450);
DISPLAY 1.021277 (-1000 450);
PAINT ORANGE (-1000 450);
DISPLAY INVISIBLE (-1000 450);
FORCEPROP 2 LAST SEC 1
J 0
(-1000 450);
PAINT MONO (-1000 450);
DISPLAY INVISIBLE (-1000 450);
FORCEADD GND..1
(-1050 50);
FORCEPROP 3 LASTPIN (-1050 100) SIG_NAME GND\g
J 0
(-1040 110);
DISPLAY 0.659574 (-1040 110);
PAINT MONO (-1040 110);
DISPLAY INVISIBLE (-1040 110);
FORCEPROP 2 LAST ROOM ST_SATA
J 0
(-1225 125);
DISPLAY 0.617021 (-1225 125);
PAINT ORANGE (-1225 125);
DISPLAY INVISIBLE (-1225 125);
FORCEPROP 1 LAST SIZE 1B
J 0
(-975 0);
DISPLAY 0.617021 (-975 0);
PAINT ORANGE (-975 0);
DISPLAY INVISIBLE (-975 0);
FORCEPROP 1 LAST VOLTAGE 0
J 0
(-1050 50);
PAINT SKYBLUE (-1050 50);
DISPLAY INVISIBLE (-1050 50);
FORCEPROP 2 LAST CDS_LIB mstr_symbols
J 0
(-1050 50);
PAINT ORANGE (-1050 50);
DISPLAY INVISIBLE (-1050 50);
FORCEPROP 1 LAST PATH I40
J 0
(-975 50);
DISPLAY 0.872340 (-975 50);
PAINT AQUA (-975 50);
DISPLAY INVISIBLE (-975 50);
FORCEPROP 1 LAST BODY_TYPE PLUMBING
J 0
(-1095 7);
DISPLAY 0.340426 (-1095 7);
PAINT GREEN (-1095 7);
DISPLAY INVISIBLE (-1095 7);
FORCEPROP 1 LAST HDL_POWER GND
J 0
(-1050 200);
DISPLAY 0.617021 (-1050 200);
PAINT GREEN (-1050 200);
DISPLAY INVISIBLE (-1050 200);
FORCEADD P5V..1
(700 750);
FORCEPROP 3 LASTPIN (700 700) SIG_NAME P5V\g
J 0
(710 710);
DISPLAY 0.659574 (710 710);
PAINT MONO (710 710);
DISPLAY INVISIBLE (710 710);
FORCEPROP 1 LAST VOLTAGE +5.0V
J 0
(775 900);
DISPLAY 1.021277 (775 900);
PAINT SKYBLUE (775 900);
DISPLAY INVISIBLE (775 900);
FORCEPROP 1 LAST SIZE 1B
J 0
(745 772);
DISPLAY 0.340426 (745 772);
PAINT GREEN (745 772);
DISPLAY INVISIBLE (745 772);
FORCEPROP 2 LAST CDS_LIB mstr_symbols
J 0
(700 750);
PAINT ORANGE (700 750);
DISPLAY INVISIBLE (700 750);
FORCEPROP 1 LAST PATH I42
J 0
(745 752);
DISPLAY 0.340426 (745 752);
PAINT GREEN (745 752);
DISPLAY INVISIBLE (745 752);
FORCEPROP 1 LAST BODY_TYPE PLUMBING
J 0
(655 707);
DISPLAY 0.340426 (655 707);
PAINT GREEN (655 707);
DISPLAY INVISIBLE (655 707);
FORCEPROP 1 LAST HDL_POWER P5V
J 0
(400 625);
DISPLAY 0.872340 (400 625);
PAINT ORANGE (400 625);
DISPLAY INVISIBLE (400 625);
FORCEADD CAP_A..2
(1225 2100);
FORCEPROP 1 LAST PART_NUMBER A36096-045
J 1
(1225 2150);
DISPLAY 0.617021 (1225 2150);
PAINT BLUE (1225 2150);
FORCEPROP 1 LAST VOLTAGE 25V
J 0
(1225 2000);
DISPLAY 0.617021 (1225 2000);
PAINT SKYBLUE (1225 2000);
FORCEPROP 1 LAST MATERIAL X7R
J 0
(1225 1950);
DISPLAY 0.617021 (1225 1950);
PAINT SKYBLUE (1225 1950);
FORCEPROP 1 LAST PACK_TYPE 0402V
J 1
(1225 1900);
DISPLAY 0.617021 (1225 1900);
PAINT SKYBLUE (1225 1900);
FORCEPROP 1 LAST VALUE 0.01UF
J 2
(1225 2000);
DISPLAY 0.617021 (1225 2000);
PAINT SKYBLUE (1225 2000);
FORCEPROP 1 LAST LOCATION C2L49
J 1
(1225 2200);
DISPLAY 0.617021 (1225 2200);
PAINT AQUA (1225 2200);
FORCEPROP 1 LAST TOLERANCE 10%
J 2
(1225 1950);
DISPLAY 0.617021 (1225 1950);
PAINT SKYBLUE (1225 1950);
FORCEPROP 1 LASTPIN (1325 2100) $PN 2
J 0
(1310 2115);
DISPLAY 0.617021 (1310 2115);
PAINT MONO (1310 2115);
FORCEPROP 1 LASTPIN (1125 2100) $PN 1
J 0
(1115 2115);
DISPLAY 0.617021 (1115 2115);
PAINT MONO (1115 2115);
FORCEPROP 2 LAST CDS_LOCATION C2L49
J 1
(1225 2200);
DISPLAY 0.617021 (1225 2200);
PAINT AQUA (1225 2200);
DISPLAY INVISIBLE (1225 2200);
FORCEPROP 2 LAST CDS_SEC 1
J 0
(1225 2250);
PAINT ORANGE (1225 2250);
DISPLAY INVISIBLE (1225 2250);
FORCEPROP 2 LAST SEC_TYPE 0402V
J 0
(1225 2350);
DISPLAY 1.404255 (1225 2350);
PAINT ORANGE (1225 2350);
DISPLAY INVISIBLE (1225 2350);
FORCEPROP 2 LAST SEC 1
J 0
(1225 2350);
DISPLAY 0.936170 (1225 2350);
PAINT MONO (1225 2350);
DISPLAY INVISIBLE (1225 2350);
FORCEPROP 1 LAST PATH I5
J 0
(1225 2300);
DISPLAY 0.978723 (1225 2300);
PAINT WHITE (1225 2300);
DISPLAY INVISIBLE (1225 2300);
FORCEPROP 2 LAST ROOM ST_SATA
J 1
(1225 2240);
DISPLAY 0.787234 (1225 2240);
PAINT SKYBLUE (1225 2240);
DISPLAY INVISIBLE (1225 2240);
FORCEPROP 2 LAST CDS_LIB dev_discrete
J 0
(1225 2100);
PAINT ORANGE (1225 2100);
DISPLAY INVISIBLE (1225 2100);
FORCEADD GND..1
(-1850 1500);
FORCEPROP 3 LASTPIN (-1850 1550) SIG_NAME GND\g
J 0
(-1840 1560);
DISPLAY 0.659574 (-1840 1560);
PAINT MONO (-1840 1560);
DISPLAY INVISIBLE (-1840 1560);
FORCEPROP 2 LAST ROOM ST_SATA
J 0
(-2025 1575);
DISPLAY 0.617021 (-2025 1575);
PAINT ORANGE (-2025 1575);
DISPLAY INVISIBLE (-2025 1575);
FORCEPROP 1 LAST SIZE 1B
J 0
(-1775 1450);
DISPLAY 0.617021 (-1775 1450);
PAINT ORANGE (-1775 1450);
DISPLAY INVISIBLE (-1775 1450);
FORCEPROP 1 LAST VOLTAGE 0
J 0
(-1850 1500);
PAINT SKYBLUE (-1850 1500);
DISPLAY INVISIBLE (-1850 1500);
FORCEPROP 1 LAST PATH I57
J 0
(-1775 1500);
DISPLAY 0.872340 (-1775 1500);
PAINT AQUA (-1775 1500);
DISPLAY INVISIBLE (-1775 1500);
FORCEPROP 2 LAST CDS_LIB mstr_symbols
J 0
(-1850 1500);
PAINT MONO (-1850 1500);
DISPLAY INVISIBLE (-1850 1500);
FORCEPROP 1 LAST BODY_TYPE PLUMBING
J 0
(-1895 1457);
DISPLAY 0.340426 (-1895 1457);
PAINT GREEN (-1895 1457);
DISPLAY INVISIBLE (-1895 1457);
FORCEPROP 1 LAST HDL_POWER GND
J 0
(-1850 1650);
DISPLAY 0.617021 (-1850 1650);
PAINT GREEN (-1850 1650);
DISPLAY INVISIBLE (-1850 1650);
FORCEADD GND..1
(-1850 2450);
FORCEPROP 3 LASTPIN (-1850 2500) SIG_NAME GND\g
J 0
(-1840 2510);
DISPLAY 0.659574 (-1840 2510);
PAINT MONO (-1840 2510);
DISPLAY INVISIBLE (-1840 2510);
FORCEPROP 2 LAST ROOM ST_SATA
J 0
(-2025 2525);
DISPLAY 0.617021 (-2025 2525);
PAINT ORANGE (-2025 2525);
DISPLAY INVISIBLE (-2025 2525);
FORCEPROP 1 LAST SIZE 1B
J 0
(-1775 2400);
DISPLAY 0.617021 (-1775 2400);
PAINT ORANGE (-1775 2400);
DISPLAY INVISIBLE (-1775 2400);
FORCEPROP 1 LAST VOLTAGE 0
J 0
(-1850 2450);
PAINT SKYBLUE (-1850 2450);
DISPLAY INVISIBLE (-1850 2450);
FORCEPROP 1 LAST PATH I58
J 0
(-1775 2450);
DISPLAY 0.872340 (-1775 2450);
PAINT AQUA (-1775 2450);
DISPLAY INVISIBLE (-1775 2450);
FORCEPROP 2 LAST CDS_LIB mstr_symbols
J 0
(-1850 2450);
PAINT MONO (-1850 2450);
DISPLAY INVISIBLE (-1850 2450);
FORCEPROP 1 LAST BODY_TYPE PLUMBING
J 0
(-1895 2407);
DISPLAY 0.340426 (-1895 2407);
PAINT GREEN (-1895 2407);
DISPLAY INVISIBLE (-1895 2407);
FORCEPROP 1 LAST HDL_POWER GND
J 0
(-1850 2600);
DISPLAY 0.617021 (-1850 2600);
PAINT GREEN (-1850 2600);
DISPLAY INVISIBLE (-1850 2600);
FORCEADD GND..1
R 1
(-1800 2200);
FORCEPROP 3 LASTPIN (-1850 2200) SIG_NAME GND\g
J 0
(-1840 2210);
DISPLAY 0.659574 (-1840 2210);
PAINT MONO (-1840 2210);
DISPLAY INVISIBLE (-1840 2210);
FORCEPROP 2 LAST ROOM ST_SATA
R 1
J 0
(-1875 2025);
DISPLAY 0.617021 (-1875 2025);
PAINT ORANGE (-1875 2025);
DISPLAY INVISIBLE (-1875 2025);
FORCEPROP 1 LAST SIZE 1B
R 1
J 0
(-1750 2275);
DISPLAY 0.617021 (-1750 2275);
PAINT ORANGE (-1750 2275);
DISPLAY INVISIBLE (-1750 2275);
FORCEPROP 1 LAST VOLTAGE 0
R 1
J 0
(-1800 2200);
PAINT SKYBLUE (-1800 2200);
DISPLAY INVISIBLE (-1800 2200);
FORCEPROP 1 LAST PATH I59
R 1
J 0
(-1800 2275);
DISPLAY 0.872340 (-1800 2275);
PAINT AQUA (-1800 2275);
DISPLAY INVISIBLE (-1800 2275);
FORCEPROP 2 LAST CDS_LIB mstr_symbols
R 1
J 0
(-1800 2200);
PAINT MONO (-1800 2200);
DISPLAY INVISIBLE (-1800 2200);
FORCEPROP 1 LAST BODY_TYPE PLUMBING
R 1
J 0
(-1757 2155);
DISPLAY 0.340426 (-1757 2155);
PAINT GREEN (-1757 2155);
DISPLAY INVISIBLE (-1757 2155);
FORCEPROP 1 LAST HDL_POWER GND
R 1
J 0
(-1950 2200);
DISPLAY 0.617021 (-1950 2200);
PAINT GREEN (-1950 2200);
DISPLAY INVISIBLE (-1950 2200);
FORCEADD CAP_A..2
(0 2300);
FORCEPROP 1 LAST VALUE 0.01UF
J 2
(0 2200);
DISPLAY 0.617021 (0 2200);
PAINT SKYBLUE (0 2200);
FORCEPROP 1 LAST MATERIAL X7R
J 0
(0 2150);
DISPLAY 0.617021 (0 2150);
PAINT SKYBLUE (0 2150);
FORCEPROP 1 LASTPIN (-100 2300) $PN 1
J 0
(-110 2315);
DISPLAY 0.617021 (-110 2315);
PAINT MONO (-110 2315);
FORCEPROP 1 LASTPIN (100 2300) $PN 2
J 0
(85 2315);
DISPLAY 0.617021 (85 2315);
PAINT MONO (85 2315);
FORCEPROP 1 LAST PACK_TYPE 0402V
J 1
(0 2100);
DISPLAY 0.617021 (0 2100);
PAINT SKYBLUE (0 2100);
FORCEPROP 1 LAST LOCATION C2L52
J 1
(0 2400);
DISPLAY 0.617021 (0 2400);
PAINT AQUA (0 2400);
FORCEPROP 1 LAST TOLERANCE 10%
J 2
(0 2150);
DISPLAY 0.617021 (0 2150);
PAINT SKYBLUE (0 2150);
FORCEPROP 1 LAST VOLTAGE 25V
J 0
(0 2200);
DISPLAY 0.617021 (0 2200);
PAINT SKYBLUE (0 2200);
FORCEPROP 1 LAST PART_NUMBER A36096-045
J 1
(0 2350);
DISPLAY 0.617021 (0 2350);
PAINT BLUE (0 2350);
FORCEPROP 2 LAST ROOM ST_SATA
J 1
(0 2440);
DISPLAY 0.787234 (0 2440);
PAINT SKYBLUE (0 2440);
DISPLAY INVISIBLE (0 2440);
FORCEPROP 1 LAST PATH I6
J 0
(0 2500);
DISPLAY 0.978723 (0 2500);
PAINT WHITE (0 2500);
DISPLAY INVISIBLE (0 2500);
FORCEPROP 2 LAST SEC 1
J 0
(0 2550);
DISPLAY 0.936170 (0 2550);
PAINT MONO (0 2550);
DISPLAY INVISIBLE (0 2550);
FORCEPROP 2 LAST SEC_TYPE 0402V
J 0
(0 2550);
DISPLAY 1.404255 (0 2550);
PAINT ORANGE (0 2550);
DISPLAY INVISIBLE (0 2550);
FORCEPROP 2 LAST CDS_SEC 1
J 0
(0 2450);
PAINT ORANGE (0 2450);
DISPLAY INVISIBLE (0 2450);
FORCEPROP 2 LAST CDS_LOCATION C2L52
J 1
(0 2400);
DISPLAY 0.617021 (0 2400);
PAINT AQUA (0 2400);
DISPLAY INVISIBLE (0 2400);
FORCEPROP 2 LAST CDS_LIB dev_discrete
J 0
(0 2300);
PAINT ORANGE (0 2300);
DISPLAY INVISIBLE (0 2300);
FORCEADD GND..1
R 1
(-1800 2050);
FORCEPROP 3 LASTPIN (-1850 2050) SIG_NAME GND\g
J 0
(-1840 2060);
DISPLAY 0.659574 (-1840 2060);
PAINT MONO (-1840 2060);
DISPLAY INVISIBLE (-1840 2060);
FORCEPROP 2 LAST ROOM ST_SATA
R 1
J 0
(-1875 1875);
DISPLAY 0.617021 (-1875 1875);
PAINT ORANGE (-1875 1875);
DISPLAY INVISIBLE (-1875 1875);
FORCEPROP 1 LAST SIZE 1B
R 1
J 0
(-1750 2125);
DISPLAY 0.617021 (-1750 2125);
PAINT ORANGE (-1750 2125);
DISPLAY INVISIBLE (-1750 2125);
FORCEPROP 1 LAST VOLTAGE 0
R 1
J 0
(-1800 2050);
PAINT SKYBLUE (-1800 2050);
DISPLAY INVISIBLE (-1800 2050);
FORCEPROP 1 LAST PATH I60
R 1
J 0
(-1800 2125);
DISPLAY 0.872340 (-1800 2125);
PAINT AQUA (-1800 2125);
DISPLAY INVISIBLE (-1800 2125);
FORCEPROP 2 LAST CDS_LIB mstr_symbols
J 0
(-1800 2050);
PAINT MONO (-1800 2050);
DISPLAY INVISIBLE (-1800 2050);
FORCEPROP 1 LAST BODY_TYPE PLUMBING
R 1
J 0
(-1757 2005);
DISPLAY 0.340426 (-1757 2005);
PAINT GREEN (-1757 2005);
DISPLAY INVISIBLE (-1757 2005);
FORCEPROP 1 LAST HDL_POWER GND
R 1
J 0
(-1950 2050);
DISPLAY 0.617021 (-1950 2050);
PAINT GREEN (-1950 2050);
DISPLAY INVISIBLE (-1950 2050);
FORCEADD GND..1
(-1850 1200);
FORCEPROP 3 LASTPIN (-1850 1250) SIG_NAME GND\g
J 0
(-1840 1260);
DISPLAY 0.659574 (-1840 1260);
PAINT MONO (-1840 1260);
DISPLAY INVISIBLE (-1840 1260);
FORCEPROP 2 LAST CDS_LIB mstr_symbols
J 0
(-1850 1200);
PAINT MONO (-1850 1200);
DISPLAY INVISIBLE (-1850 1200);
FORCEPROP 1 LAST PATH I61
J 0
(-1775 1200);
DISPLAY 0.872340 (-1775 1200);
PAINT AQUA (-1775 1200);
DISPLAY INVISIBLE (-1775 1200);
FORCEPROP 2 LAST ROOM ST_SATA
J 0
(-2025 1275);
DISPLAY 0.617021 (-2025 1275);
PAINT ORANGE (-2025 1275);
DISPLAY INVISIBLE (-2025 1275);
FORCEPROP 1 LAST SIZE 1B
J 0
(-1775 1150);
DISPLAY 0.617021 (-1775 1150);
PAINT ORANGE (-1775 1150);
DISPLAY INVISIBLE (-1775 1150);
FORCEPROP 1 LAST VOLTAGE 0
J 0
(-1850 1200);
PAINT SKYBLUE (-1850 1200);
DISPLAY INVISIBLE (-1850 1200);
FORCEPROP 1 LAST BODY_TYPE PLUMBING
J 0
(-1895 1157);
DISPLAY 0.340426 (-1895 1157);
PAINT GREEN (-1895 1157);
DISPLAY INVISIBLE (-1895 1157);
FORCEPROP 1 LAST HDL_POWER GND
J 0
(-1850 1350);
DISPLAY 0.617021 (-1850 1350);
PAINT GREEN (-1850 1350);
DISPLAY INVISIBLE (-1850 1350);
FORCEADD GND..1
R 1
(-1800 950);
FORCEPROP 3 LASTPIN (-1850 950) SIG_NAME GND\g
J 0
(-1840 960);
DISPLAY 0.659574 (-1840 960);
PAINT MONO (-1840 960);
DISPLAY INVISIBLE (-1840 960);
FORCEPROP 2 LAST CDS_LIB mstr_symbols
J 0
(-1800 950);
PAINT MONO (-1800 950);
DISPLAY INVISIBLE (-1800 950);
FORCEPROP 1 LAST PATH I62
R 1
J 0
(-1800 1025);
DISPLAY 0.872340 (-1800 1025);
PAINT AQUA (-1800 1025);
DISPLAY INVISIBLE (-1800 1025);
FORCEPROP 2 LAST ROOM ST_SATA
R 1
J 0
(-1875 775);
DISPLAY 0.617021 (-1875 775);
PAINT ORANGE (-1875 775);
DISPLAY INVISIBLE (-1875 775);
FORCEPROP 1 LAST SIZE 1B
R 1
J 0
(-1750 1025);
DISPLAY 0.617021 (-1750 1025);
PAINT ORANGE (-1750 1025);
DISPLAY INVISIBLE (-1750 1025);
FORCEPROP 1 LAST VOLTAGE 0
R 1
J 0
(-1800 950);
PAINT SKYBLUE (-1800 950);
DISPLAY INVISIBLE (-1800 950);
FORCEPROP 1 LAST BODY_TYPE PLUMBING
R 1
J 0
(-1757 905);
DISPLAY 0.340426 (-1757 905);
PAINT GREEN (-1757 905);
DISPLAY INVISIBLE (-1757 905);
FORCEPROP 1 LAST HDL_POWER GND
R 1
J 0
(-1950 950);
DISPLAY 0.617021 (-1950 950);
PAINT GREEN (-1950 950);
DISPLAY INVISIBLE (-1950 950);
FORCEADD GND..1
R 1
(-1800 800);
FORCEPROP 3 LASTPIN (-1850 800) SIG_NAME GND\g
J 0
(-1840 810);
DISPLAY 0.659574 (-1840 810);
PAINT MONO (-1840 810);
DISPLAY INVISIBLE (-1840 810);
FORCEPROP 2 LAST ROOM ST_SATA
R 1
J 0
(-1875 625);
DISPLAY 0.617021 (-1875 625);
PAINT ORANGE (-1875 625);
DISPLAY INVISIBLE (-1875 625);
FORCEPROP 1 LAST SIZE 1B
R 1
J 0
(-1750 875);
DISPLAY 0.617021 (-1750 875);
PAINT ORANGE (-1750 875);
DISPLAY INVISIBLE (-1750 875);
FORCEPROP 1 LAST VOLTAGE 0
R 1
J 0
(-1800 800);
PAINT SKYBLUE (-1800 800);
DISPLAY INVISIBLE (-1800 800);
FORCEPROP 2 LAST CDS_LIB mstr_symbols
J 0
(-1800 800);
PAINT MONO (-1800 800);
DISPLAY INVISIBLE (-1800 800);
FORCEPROP 1 LAST PATH I63
R 1
J 0
(-1800 875);
DISPLAY 0.872340 (-1800 875);
PAINT AQUA (-1800 875);
DISPLAY INVISIBLE (-1800 875);
FORCEPROP 1 LAST BODY_TYPE PLUMBING
R 1
J 0
(-1757 755);
DISPLAY 0.340426 (-1757 755);
PAINT GREEN (-1757 755);
DISPLAY INVISIBLE (-1757 755);
FORCEPROP 1 LAST HDL_POWER GND
R 1
J 0
(-1950 800);
DISPLAY 0.617021 (-1950 800);
PAINT GREEN (-1950 800);
DISPLAY INVISIBLE (-1950 800);
FORCEADD GND..1
(-1850 250);
FORCEPROP 3 LASTPIN (-1850 300) SIG_NAME GND\g
J 0
(-1840 310);
DISPLAY 0.659574 (-1840 310);
PAINT MONO (-1840 310);
DISPLAY INVISIBLE (-1840 310);
FORCEPROP 1 LAST VOLTAGE 0
J 0
(-1850 250);
PAINT SKYBLUE (-1850 250);
DISPLAY INVISIBLE (-1850 250);
FORCEPROP 1 LAST SIZE 1B
J 0
(-1775 200);
DISPLAY 0.617021 (-1775 200);
PAINT ORANGE (-1775 200);
DISPLAY INVISIBLE (-1775 200);
FORCEPROP 2 LAST ROOM ST_SATA
J 0
(-2025 325);
DISPLAY 0.617021 (-2025 325);
PAINT ORANGE (-2025 325);
DISPLAY INVISIBLE (-2025 325);
FORCEPROP 1 LAST PATH I64
J 0
(-1775 250);
DISPLAY 0.872340 (-1775 250);
PAINT AQUA (-1775 250);
DISPLAY INVISIBLE (-1775 250);
FORCEPROP 2 LAST CDS_LIB mstr_symbols
J 0
(-1850 250);
PAINT MONO (-1850 250);
DISPLAY INVISIBLE (-1850 250);
FORCEPROP 1 LAST BODY_TYPE PLUMBING
J 0
(-1895 207);
DISPLAY 0.340426 (-1895 207);
PAINT GREEN (-1895 207);
DISPLAY INVISIBLE (-1895 207);
FORCEPROP 1 LAST HDL_POWER GND
J 0
(-1850 400);
DISPLAY 0.617021 (-1850 400);
PAINT GREEN (-1850 400);
DISPLAY INVISIBLE (-1850 400);
FORCEADD FUSE..1
R 4
(975 450);
FORCEPROP 1 LAST MATERIAL IC
J 0
(825 525);
DISPLAY 0.617021 (825 525);
PAINT SKYBLUE (825 525);
FORCEPROP 1 LAST LOCATION F9B1
J 0
(825 575);
DISPLAY 0.617021 (825 575);
PAINT AQUA (825 575);
FORCEPROP 1 LAST PART_NUMBER C94311-016
J 0
(825 375);
DISPLAY 0.617021 (825 375);
PAINT BLUE (825 375);
FORCEPROP 1 LASTPIN (1125 450) $PN 1
J 0
(1115 465);
DISPLAY 0.617021 (1115 465);
PAINT ORANGE (1115 465);
FORCEPROP 1 LASTPIN (825 450) $PN 2
J 0
(815 465);
DISPLAY 0.617021 (815 465);
PAINT ORANGE (815 465);
FORCEPROP 1 LAST PATH I66
R 2
J 0
(675 400);
DISPLAY 0.978723 (675 400);
PAINT BLUE (675 400);
DISPLAY INVISIBLE (675 400);
FORCEPROP 0 LAST CDS_SEC 1
R 2
J 0
(1125 300);
PAINT MONO (1125 300);
DISPLAY INVISIBLE (1125 300);
FORCEPROP 2 LAST CDS_LIB mstr_discrete
R 2
J 0
(975 450);
PAINT ORANGE (975 450);
DISPLAY INVISIBLE (975 450);
FORCEPROP 0 LAST ROOM ST_SATA
R 2
J 0
(1125 250);
DISPLAY 1.021277 (1125 250);
PAINT ORANGE (1125 250);
DISPLAY INVISIBLE (1125 250);
FORCEPROP 1 LAST PACK_TYPE SM
R 2
J 0
(1125 300);
DISPLAY 0.978723 (1125 300);
PAINT SKYBLUE (1125 300);
DISPLAY INVISIBLE (1125 300);
FORCEPROP 2 LAST SEC_TYPE SM
R 2
J 0
(1125 300);
DISPLAY 1.021277 (1125 300);
PAINT ORANGE (1125 300);
DISPLAY INVISIBLE (1125 300);
FORCEPROP 2 LAST SEC 1
R 2
J 0
(1125 300);
PAINT MONO (1125 300);
DISPLAY INVISIBLE (1125 300);
FORCEPROP 2 LAST CDS_LOCATION F9B1
R 2
J 0
(1125 350);
DISPLAY 0.617021 (1125 350);
PAINT AQUA (1125 350);
DISPLAY INVISIBLE (1125 350);
FORCEADD SKT-SATA7P-6P-165-GP-U1..1
(-2300 800);
FORCEPROP 2 LASTPIN (-2050 600) $PN P3
J 0
(-2040 610);
DISPLAY 0.808511 (-2040 610);
PAINT ORANGE (-2040 610);
FORCEPROP 2 LASTPIN (-2050 700) $PN P1
J 0
(-2040 710);
DISPLAY 0.808511 (-2040 710);
PAINT ORANGE (-2040 710);
FORCEPROP 2 LASTPIN (-2050 800) $PN S7
J 0
(-2040 810);
DISPLAY 0.808511 (-2040 810);
PAINT ORANGE (-2040 810);
FORCEPROP 2 LASTPIN (-2050 450) $PN P6
J 0
(-2040 460);
DISPLAY 0.808511 (-2040 460);
PAINT ORANGE (-2040 460);
FORCEPROP 2 LASTPIN (-2050 650) $PN P2
J 0
(-2040 660);
DISPLAY 0.808511 (-2040 660);
PAINT ORANGE (-2040 660);
FORCEPROP 1 LAST VALUE SKT-SATA7P-6P-165-GP-U1
J 0
(-2400 251);
DISPLAY 0.617021 (-2400 251);
PAINT GREEN (-2400 251);
FORCEPROP 2 LASTPIN (-2050 1150) $PN S1
J 0
(-2040 1160);
DISPLAY 0.808511 (-2040 1160);
PAINT ORANGE (-2040 1160);
FORCEPROP 2 LASTPIN (-2050 1050) $PN S2
J 0
(-2040 1060);
DISPLAY 0.808511 (-2040 1060);
PAINT ORANGE (-2040 1060);
FORCEPROP 2 LASTPIN (-2050 950) $PN S4
J 0
(-2040 960);
DISPLAY 0.808511 (-2040 960);
PAINT ORANGE (-2040 960);
FORCEPROP 2 LASTPIN (-2050 900) $PN S5
J 0
(-2040 910);
DISPLAY 0.808511 (-2040 910);
PAINT ORANGE (-2040 910);
FORCEPROP 2 LASTPIN (-2050 850) $PN S6
J 0
(-2040 860);
DISPLAY 0.808511 (-2040 860);
PAINT ORANGE (-2040 860);
FORCEPROP 2 LASTPIN (-2050 550) $PN P4
J 0
(-2040 560);
DISPLAY 0.808511 (-2040 560);
PAINT ORANGE (-2040 560);
FORCEPROP 2 LASTPIN (-2050 500) $PN P5
J 0
(-2040 510);
DISPLAY 0.808511 (-2040 510);
PAINT ORANGE (-2040 510);
FORCEPROP 2 LASTPIN (-2150 1200) $PN NP1
J 0
(-2140 1210);
DISPLAY 0.808511 (-2140 1210);
PAINT ORANGE (-2140 1210);
FORCEPROP 2 LASTPIN (-2150 400) $PN NP2
J 0
(-2140 410);
DISPLAY 0.808511 (-2140 410);
PAINT ORANGE (-2140 410);
FORCEPROP 2 LASTPIN (-2050 1250) $PN H1
J 0
(-2040 1260);
DISPLAY 0.808511 (-2040 1260);
PAINT ORANGE (-2040 1260);
FORCEPROP 2 LASTPIN (-2050 350) $PN H2
J 0
(-2040 360);
DISPLAY 0.808511 (-2040 360);
PAINT ORANGE (-2040 360);
FORCEPROP 1 LAST LOCATION J2W1
J 0
(-2405 1330);
DISPLAY 0.617021 (-2405 1330);
PAINT GREEN (-2405 1330);
FORCEPROP 2 LASTPIN (-2050 1000) $PN S3
J 0
(-2040 1010);
DISPLAY 0.808511 (-2040 1010);
PAINT ORANGE (-2040 1010);
FORCEPROP 0 LAST BOM_SS NOPOP
J 0
(-2400 175);
DISPLAY 1.021277 (-2400 175);
PAINT BROWN (-2400 175);
DISPLAY BOTH (-2400 175);
FORCEPROP 1 LAST CDS_LMAN_SYM_OUTLINE -100,500,100,-500
J 0
(-2300 800);
DISPLAY 0.468085 (-2300 800);
PAINT GREEN (-2300 800);
DISPLAY INVISIBLE (-2300 800);
FORCEPROP 1 LAST PATH I67
J 0
(-2300 800);
DISPLAY 0.617021 (-2300 800);
PAINT GREEN (-2300 800);
DISPLAY INVISIBLE (-2300 800);
FORCEPROP 1 LAST PART_NUMBER 022.10014.0121
J 0
(-2300 800);
DISPLAY 0.617021 (-2300 800);
PAINT GREEN (-2300 800);
DISPLAY INVISIBLE (-2300 800);
FORCEPROP 2 LAST CDS_LIB w_hdl
J 0
(-2300 800);
PAINT MONO (-2300 800);
DISPLAY INVISIBLE (-2300 800);
FORCEPROP 2 LAST SEC_TYPE SOCKET-G6
J 0
(-2400 1375);
DISPLAY 1.021277 (-2400 1375);
PAINT ORANGE (-2400 1375);
DISPLAY INVISIBLE (-2400 1375);
FORCEPROP 2 LAST SEC 1
J 0
(-2400 1375);
DISPLAY 0.680851 (-2400 1375);
PAINT MONO (-2400 1375);
DISPLAY INVISIBLE (-2400 1375);
FORCEPROP 1 LAST PACK_TYPE SOCKET-G6
J 0
(-2300 800);
DISPLAY 0.617021 (-2300 800);
PAINT GREEN (-2300 800);
DISPLAY INVISIBLE (-2300 800);
FORCEADD SKT-SATA7P-6P-165-GP-U1..1
(-2300 2050);
FORCEPROP 2 LASTPIN (-2050 1700) $PN P6
J 0
(-2040 1710);
DISPLAY 0.808511 (-2040 1710);
PAINT ORANGE (-2040 1710);
FORCEPROP 2 LASTPIN (-2050 1600) $PN H2
J 0
(-2040 1610);
DISPLAY 0.808511 (-2040 1610);
PAINT ORANGE (-2040 1610);
FORCEPROP 2 LASTPIN (-2050 1900) $PN P2
J 0
(-2040 1910);
DISPLAY 0.808511 (-2040 1910);
PAINT ORANGE (-2040 1910);
FORCEPROP 2 LASTPIN (-2050 2500) $PN H1
J 0
(-2040 2510);
DISPLAY 0.808511 (-2040 2510);
PAINT ORANGE (-2040 2510);
FORCEPROP 2 LASTPIN (-2150 1650) $PN NP2
J 0
(-2140 1660);
DISPLAY 0.808511 (-2140 1660);
PAINT ORANGE (-2140 1660);
FORCEPROP 2 LASTPIN (-2150 2450) $PN NP1
J 0
(-2140 2460);
DISPLAY 0.808511 (-2140 2460);
PAINT ORANGE (-2140 2460);
FORCEPROP 2 LASTPIN (-2050 1750) $PN P5
J 0
(-2040 1760);
DISPLAY 0.808511 (-2040 1760);
PAINT ORANGE (-2040 1760);
FORCEPROP 2 LASTPIN (-2050 1850) $PN P3
J 0
(-2040 1860);
DISPLAY 0.808511 (-2040 1860);
PAINT ORANGE (-2040 1860);
FORCEPROP 2 LASTPIN (-2050 1950) $PN P1
J 0
(-2040 1960);
DISPLAY 0.808511 (-2040 1960);
PAINT ORANGE (-2040 1960);
FORCEPROP 2 LASTPIN (-2050 2050) $PN S7
J 0
(-2040 2060);
DISPLAY 0.808511 (-2040 2060);
PAINT ORANGE (-2040 2060);
FORCEPROP 2 LASTPIN (-2050 2100) $PN S6
J 0
(-2040 2110);
DISPLAY 0.808511 (-2040 2110);
PAINT ORANGE (-2040 2110);
FORCEPROP 2 LASTPIN (-2050 2150) $PN S5
J 0
(-2040 2160);
DISPLAY 0.808511 (-2040 2160);
PAINT ORANGE (-2040 2160);
FORCEPROP 2 LASTPIN (-2050 2250) $PN S3
J 0
(-2040 2260);
DISPLAY 0.808511 (-2040 2260);
PAINT ORANGE (-2040 2260);
FORCEPROP 2 LASTPIN (-2050 2400) $PN S1
J 0
(-2040 2410);
DISPLAY 0.808511 (-2040 2410);
PAINT ORANGE (-2040 2410);
FORCEPROP 1 LAST LOCATION J2W2
J 0
(-2405 2580);
DISPLAY 0.617021 (-2405 2580);
PAINT GREEN (-2405 2580);
FORCEPROP 2 LASTPIN (-2050 1800) $PN P4
J 0
(-2040 1810);
DISPLAY 0.808511 (-2040 1810);
PAINT ORANGE (-2040 1810);
FORCEPROP 1 LAST VALUE SKT-SATA7P-6P-165-GP-U1
J 0
(-2400 1501);
DISPLAY 0.617021 (-2400 1501);
PAINT GREEN (-2400 1501);
FORCEPROP 2 LASTPIN (-2050 2300) $PN S2
J 0
(-2040 2310);
DISPLAY 0.808511 (-2040 2310);
PAINT ORANGE (-2040 2310);
FORCEPROP 0 LAST BOM_DS NOPOP
J 0
(-2400 1425);
DISPLAY 1.021277 (-2400 1425);
PAINT BROWN (-2400 1425);
DISPLAY BOTH (-2400 1425);
FORCEPROP 2 LASTPIN (-2050 2200) $PN S4
J 0
(-2040 2210);
DISPLAY 0.808511 (-2040 2210);
PAINT ORANGE (-2040 2210);
FORCEPROP 1 LAST PACK_TYPE SOCKET-G6
J 0
(-2300 2050);
DISPLAY 0.617021 (-2300 2050);
PAINT GREEN (-2300 2050);
DISPLAY INVISIBLE (-2300 2050);
FORCEPROP 2 LAST SEC 1
J 0
(-2400 2625);
DISPLAY 0.680851 (-2400 2625);
PAINT MONO (-2400 2625);
DISPLAY INVISIBLE (-2400 2625);
FORCEPROP 2 LAST SEC_TYPE SOCKET-G6
J 0
(-2400 2625);
DISPLAY 1.021277 (-2400 2625);
PAINT ORANGE (-2400 2625);
DISPLAY INVISIBLE (-2400 2625);
FORCEPROP 2 LAST CDS_LIB w_hdl
J 0
(-2300 2050);
PAINT MONO (-2300 2050);
DISPLAY INVISIBLE (-2300 2050);
FORCEPROP 1 LAST PART_NUMBER 022.10014.0121
J 0
(-2300 2050);
DISPLAY 0.617021 (-2300 2050);
PAINT GREEN (-2300 2050);
DISPLAY INVISIBLE (-2300 2050);
FORCEPROP 1 LAST CDS_LMAN_SYM_OUTLINE -100,500,100,-500
J 0
(-2300 2050);
DISPLAY 0.468085 (-2300 2050);
PAINT GREEN (-2300 2050);
DISPLAY INVISIBLE (-2300 2050);
FORCEPROP 1 LAST PATH I68
J 0
(-2300 2050);
DISPLAY 0.617021 (-2300 2050);
PAINT GREEN (-2300 2050);
DISPLAY INVISIBLE (-2300 2050);
FORCEADD GND..1
R 1
(-1800 550);
FORCEPROP 3 LASTPIN (-1850 550) SIG_NAME GND\g
J 0
(-1840 560);
DISPLAY 0.659574 (-1840 560);
PAINT MONO (-1840 560);
DISPLAY INVISIBLE (-1840 560);
FORCEPROP 2 LAST ROOM ST_SATA
R 1
J 0
(-1875 375);
DISPLAY 0.617021 (-1875 375);
PAINT ORANGE (-1875 375);
DISPLAY INVISIBLE (-1875 375);
FORCEPROP 1 LAST SIZE 1B
R 1
J 0
(-1750 625);
DISPLAY 0.617021 (-1750 625);
PAINT ORANGE (-1750 625);
DISPLAY INVISIBLE (-1750 625);
FORCEPROP 1 LAST VOLTAGE 0
R 1
J 0
(-1800 550);
PAINT SKYBLUE (-1800 550);
DISPLAY INVISIBLE (-1800 550);
FORCEPROP 2 LAST CDS_LIB mstr_symbols
J 0
(-1800 550);
PAINT MONO (-1800 550);
DISPLAY INVISIBLE (-1800 550);
FORCEPROP 1 LAST PATH I69
R 1
J 0
(-1800 625);
DISPLAY 0.872340 (-1800 625);
PAINT AQUA (-1800 625);
DISPLAY INVISIBLE (-1800 625);
FORCEPROP 1 LAST BODY_TYPE PLUMBING
R 1
J 0
(-1757 505);
DISPLAY 0.340426 (-1757 505);
PAINT GREEN (-1757 505);
DISPLAY INVISIBLE (-1757 505);
FORCEPROP 1 LAST HDL_POWER GND
R 1
J 0
(-1950 550);
DISPLAY 0.617021 (-1950 550);
PAINT GREEN (-1950 550);
DISPLAY INVISIBLE (-1950 550);
FORCEADD CAP_A..2
(350 2150);
FORCEPROP 1 LAST VOLTAGE 25V
J 0
(350 2050);
DISPLAY 0.617021 (350 2050);
PAINT SKYBLUE (350 2050);
FORCEPROP 1 LAST MATERIAL X7R
J 0
(350 2000);
DISPLAY 0.617021 (350 2000);
PAINT SKYBLUE (350 2000);
FORCEPROP 1 LAST PACK_TYPE 0402V
J 1
(350 1950);
DISPLAY 0.617021 (350 1950);
PAINT SKYBLUE (350 1950);
FORCEPROP 1 LAST TOLERANCE 10%
J 2
(350 2000);
DISPLAY 0.617021 (350 2000);
PAINT SKYBLUE (350 2000);
FORCEPROP 1 LAST PART_NUMBER A36096-045
J 1
(350 2200);
DISPLAY 0.617021 (350 2200);
PAINT BLUE (350 2200);
FORCEPROP 1 LAST LOCATION C2L50
J 1
(350 2250);
DISPLAY 0.617021 (350 2250);
PAINT AQUA (350 2250);
FORCEPROP 1 LASTPIN (450 2150) $PN 2
J 0
(435 2165);
DISPLAY 0.617021 (435 2165);
PAINT MONO (435 2165);
FORCEPROP 1 LAST VALUE 0.01UF
J 2
(350 2050);
DISPLAY 0.617021 (350 2050);
PAINT SKYBLUE (350 2050);
FORCEPROP 1 LASTPIN (250 2150) $PN 1
J 0
(240 2165);
DISPLAY 0.617021 (240 2165);
PAINT MONO (240 2165);
FORCEPROP 2 LAST CDS_LOCATION C2L50
J 1
(350 2250);
DISPLAY 0.617021 (350 2250);
PAINT AQUA (350 2250);
DISPLAY INVISIBLE (350 2250);
FORCEPROP 2 LAST CDS_SEC 1
J 0
(350 2300);
PAINT ORANGE (350 2300);
DISPLAY INVISIBLE (350 2300);
FORCEPROP 2 LAST SEC_TYPE 0402V
J 0
(350 2400);
DISPLAY 1.404255 (350 2400);
PAINT ORANGE (350 2400);
DISPLAY INVISIBLE (350 2400);
FORCEPROP 2 LAST SEC 1
J 0
(350 2400);
DISPLAY 0.936170 (350 2400);
PAINT MONO (350 2400);
DISPLAY INVISIBLE (350 2400);
FORCEPROP 1 LAST PATH I7
J 0
(350 2350);
DISPLAY 0.978723 (350 2350);
PAINT WHITE (350 2350);
DISPLAY INVISIBLE (350 2350);
FORCEPROP 2 LAST ROOM ST_SATA
J 1
(350 2290);
DISPLAY 0.787234 (350 2290);
PAINT SKYBLUE (350 2290);
DISPLAY INVISIBLE (350 2290);
FORCEPROP 2 LAST CDS_LIB dev_discrete
J 0
(350 2150);
PAINT ORANGE (350 2150);
DISPLAY INVISIBLE (350 2150);
FORCEADD GND..1
R 1
(-1800 1800);
FORCEPROP 3 LASTPIN (-1850 1800) SIG_NAME GND\g
J 0
(-1840 1810);
DISPLAY 0.659574 (-1840 1810);
PAINT MONO (-1840 1810);
DISPLAY INVISIBLE (-1840 1810);
FORCEPROP 1 LAST PATH I70
R 1
J 0
(-1800 1875);
DISPLAY 0.872340 (-1800 1875);
PAINT AQUA (-1800 1875);
DISPLAY INVISIBLE (-1800 1875);
FORCEPROP 2 LAST CDS_LIB mstr_symbols
J 0
(-1800 1800);
PAINT MONO (-1800 1800);
DISPLAY INVISIBLE (-1800 1800);
FORCEPROP 1 LAST VOLTAGE 0
R 1
J 0
(-1800 1800);
PAINT SKYBLUE (-1800 1800);
DISPLAY INVISIBLE (-1800 1800);
FORCEPROP 1 LAST SIZE 1B
R 1
J 0
(-1750 1875);
DISPLAY 0.617021 (-1750 1875);
PAINT ORANGE (-1750 1875);
DISPLAY INVISIBLE (-1750 1875);
FORCEPROP 2 LAST ROOM ST_SATA
R 1
J 0
(-1875 1625);
DISPLAY 0.617021 (-1875 1625);
PAINT ORANGE (-1875 1625);
DISPLAY INVISIBLE (-1875 1625);
FORCEPROP 1 LAST BODY_TYPE PLUMBING
R 1
J 0
(-1757 1755);
DISPLAY 0.340426 (-1757 1755);
PAINT GREEN (-1757 1755);
DISPLAY INVISIBLE (-1757 1755);
FORCEPROP 1 LAST HDL_POWER GND
R 1
J 0
(-1950 1800);
DISPLAY 0.617021 (-1950 1800);
PAINT GREEN (-1950 1800);
DISPLAY INVISIBLE (-1950 1800);
FORCEADD FUSE-3A75V-GP..1
(175 650);
FORCEPROP 1 LAST LOCATION F8B1
J 0
(100 710);
DISPLAY 0.617021 (100 710);
PAINT GREEN (100 710);
FORCEPROP 2 LASTPIN (-50 650) $PN 1
J 2
(-60 660);
DISPLAY 0.808511 (-60 660);
PAINT ORANGE (-60 660);
FORCEPROP 2 LASTPIN (400 650) $PN 2
J 0
(410 660);
DISPLAY 0.808511 (410 660);
PAINT ORANGE (410 660);
FORCEPROP 1 LAST VALUE FUSE-3A75V-GP
J 0
(100 570);
DISPLAY 0.617021 (100 570);
PAINT GREEN (100 570);
FORCEPROP 2 LAST CDS_LIB w_hdl
J 0
(175 650);
PAINT MONO (175 650);
DISPLAY INVISIBLE (175 650);
FORCEPROP 1 LAST PART_NUMBER 69.43001.511
J 0
(175 650);
DISPLAY 0.617021 (175 650);
PAINT GREEN (175 650);
DISPLAY INVISIBLE (175 650);
FORCEPROP 1 LAST PATH I71
J 0
(175 650);
DISPLAY 0.617021 (175 650);
PAINT GREEN (175 650);
DISPLAY INVISIBLE (175 650);
FORCEPROP 1 LAST CDS_LMAN_SYM_OUTLINE -75,50,75,-50
J 0
(175 650);
DISPLAY 0.468085 (175 650);
PAINT GREEN (175 650);
DISPLAY INVISIBLE (175 650);
FORCEPROP 1 LAST PACK_TYPE DISCRET-G5
J 0
(175 650);
DISPLAY 0.617021 (175 650);
PAINT GREEN (175 650);
DISPLAY INVISIBLE (175 650);
FORCEPROP 2 LAST SEC 1
J 0
(100 750);
DISPLAY 0.680851 (100 750);
PAINT MONO (100 750);
DISPLAY INVISIBLE (100 750);
FORCEPROP 2 LAST SEC_TYPE DISCRET-G5
J 0
(100 750);
DISPLAY 1.021277 (100 750);
PAINT ORANGE (100 750);
DISPLAY INVISIBLE (100 750);
FORCEADD CAP_A..2
(750 2250);
FORCEPROP 1 LAST LOCATION C2L51
J 1
(750 2350);
DISPLAY 0.617021 (750 2350);
PAINT AQUA (750 2350);
FORCEPROP 1 LAST VALUE 0.01UF
J 2
(750 2150);
DISPLAY 0.617021 (750 2150);
PAINT SKYBLUE (750 2150);
FORCEPROP 1 LAST VOLTAGE 25V
J 0
(750 2150);
DISPLAY 0.617021 (750 2150);
PAINT SKYBLUE (750 2150);
FORCEPROP 1 LAST TOLERANCE 10%
J 2
(750 2100);
DISPLAY 0.617021 (750 2100);
PAINT SKYBLUE (750 2100);
FORCEPROP 1 LAST PACK_TYPE 0402V
J 1
(750 2050);
DISPLAY 0.617021 (750 2050);
PAINT SKYBLUE (750 2050);
FORCEPROP 1 LAST MATERIAL X7R
J 0
(750 2100);
DISPLAY 0.617021 (750 2100);
PAINT SKYBLUE (750 2100);
FORCEPROP 1 LASTPIN (850 2250) $PN 2
J 0
(835 2265);
DISPLAY 0.617021 (835 2265);
PAINT MONO (835 2265);
FORCEPROP 1 LAST PART_NUMBER A36096-045
J 1
(750 2300);
DISPLAY 0.617021 (750 2300);
PAINT BLUE (750 2300);
FORCEPROP 1 LASTPIN (650 2250) $PN 1
J 0
(640 2265);
DISPLAY 0.617021 (640 2265);
PAINT MONO (640 2265);
FORCEPROP 2 LAST CDS_LOCATION C2L51
J 1
(750 2350);
DISPLAY 0.617021 (750 2350);
PAINT AQUA (750 2350);
DISPLAY INVISIBLE (750 2350);
FORCEPROP 2 LAST ROOM ST_SATA
J 1
(750 2390);
DISPLAY 0.787234 (750 2390);
PAINT SKYBLUE (750 2390);
DISPLAY INVISIBLE (750 2390);
FORCEPROP 1 LAST PATH I8
J 0
(750 2450);
DISPLAY 0.978723 (750 2450);
PAINT WHITE (750 2450);
DISPLAY INVISIBLE (750 2450);
FORCEPROP 2 LAST SEC 1
J 0
(750 2500);
DISPLAY 0.936170 (750 2500);
PAINT MONO (750 2500);
DISPLAY INVISIBLE (750 2500);
FORCEPROP 2 LAST SEC_TYPE 0402V
J 0
(750 2500);
DISPLAY 1.404255 (750 2500);
PAINT ORANGE (750 2500);
DISPLAY INVISIBLE (750 2500);
FORCEPROP 2 LAST CDS_SEC 1
J 0
(750 2400);
PAINT ORANGE (750 2400);
DISPLAY INVISIBLE (750 2400);
FORCEPROP 2 LAST CDS_LIB dev_discrete
J 0
(750 2250);
PAINT ORANGE (750 2250);
DISPLAY INVISIBLE (750 2250);
FORCEADD OFFPAGE..2
(2125 2150);
FORCEPROP 2 LAST $XR0 116 
J 0
(2314 2150);
DISPLAY 0.638298 (2314 2150);
PAINT MONO (2314 2150);
FORCEPROP 2 LAST PATH I9
J 0
(2325 2200);
DISPLAY 1.021277 (2325 2200);
PAINT ORANGE (2325 2200);
DISPLAY INVISIBLE (2325 2200);
FORCEPROP 2 LAST CDS_LIB mstr_standard
J 0
(2125 2150);
DISPLAY 1.382979 (2125 2150);
PAINT ORANGE (2125 2150);
DISPLAY INVISIBLE (2125 2150);
FORCEPROP 2 LAST ROOM ST_SATA
J 0
(2325 2200);
DISPLAY 1.404255 (2325 2200);
PAINT ORANGE (2325 2200);
DISPLAY INVISIBLE (2325 2200);
FORCEPROP 1 LAST OFFPAGE TRUE
J 0
(2450 2025);
PAINT GREEN (2450 2025);
DISPLAY INVISIBLE (2450 2025);
FORCEPROP 1 LAST COMMENT_BODY TRUE
J 0
(2080 2055);
DISPLAY 1.170213 (2080 2055);
PAINT GREEN (2080 2055);
DISPLAY INVISIBLE (2080 2055);
FORCEADD INTEL_CORP_BPAGE..1
(3400 -2050);
FORCEPROP 1 LAST CDS_CON_LAST_MODIFIED Fri Jun 16 17:49:03 2017
J 0
(1975 -1725);
DISPLAY 1.361702 (1975 -1725);
PAINT GREEN (1975 -1725);
DISPLAY INVISIBLE (1975 -1725);
FORCEPROP 1 LAST CUSTOM_TXT_CDS <CURRENT_DESIGN_SHEET> OF <TOTAL_DESIGN_SHEETS>
J 0
(2900 -2025);
PAINT ORANGE (2900 -2025);
FORCEPROP 2 LAST CUSTOM_TXT_CDS <XR_PAGE_TITLE>
J 0
(-4490 3200);
DISPLAY 0.638298 (-4490 3200);
PAINT PINK (-4490 3200);
DISPLAY INVISIBLE (-4490 3200);
FORCEPROP 2 LAST CUSTOM_TXT_CDS <CON_LAST_MODIFIED>
J 0
(-600 -1950);
DISPLAY 1.361702 (-600 -1950);
PAINT ORANGE (-600 -1950);
FORCEPROP 1 LAST SCH_TITLE SATA DOWN CONNECTOR
J 0
(-4550 -2000);
DISPLAY 1.212766 (-4550 -2000);
PAINT ORANGE (-4550 -2000);
FORCEPROP 2 LAST CDS_LIB mstr_symbols
J 0
(3400 -2050);
DISPLAY 1.361702 (3400 -2050);
PAINT ORANGE (3400 -2050);
DISPLAY INVISIBLE (3400 -2050);
FORCEPROP 2 LAST PAGE_BORDER TRUE
J 0
(-4490 3200);
DISPLAY 0.872340 (-4490 3200);
PAINT PINK (-4490 3200);
DISPLAY INVISIBLE (-4490 3200);
FORCEPROP 2 LAST BOM_COST ST_SATA
J 0
(-4475 3250);
PAINT MONO (-4475 3250);
DISPLAY INVISIBLE (-4475 3250);
FORCEPROP 1 LAST COMMENT_BODY TRUE
J 0
(3412 -2038);
DISPLAY 0.617021 (3412 -2038);
PAINT GREEN (3412 -2038);
DISPLAY INVISIBLE (3412 -2038);
FORCEPROP 2 LAST CDS_XR_PAGE_TITLE CR-172 : @BASEBOARD_FAB2_LIB.BASEBOARD_FAB2(SCH_1):PAGE172
J 0
(-4490 3200);
DISPLAY 0.638298 (-4490 3200);
PAINT PINK (-4490 3200);
DISPLAY INVISIBLE (-4490 3200);
FORCEADD DESIGN_NOTE..1
(-3275 1800);
FORCEPROP 0 LAST L1 PLACE ON THE PRIMARY SIDE
J 0
(-3750 1675);
DISPLAY 0.829787 (-3750 1675);
PAINT WHITE (-3750 1675);
FORCEPROP 0 LAST L2 POPULATE FOR SINGLE SIDED BOARD
J 0
(-3750 1625);
DISPLAY 0.808511 (-3750 1625);
PAINT ORANGE (-3750 1625);
FORCEPROP 2 LAST ROOM ST_SATA
J 0
(-3400 1625);
DISPLAY 1.361702 (-3400 1625);
PAINT ORANGE (-3400 1625);
DISPLAY INVISIBLE (-3400 1625);
FORCEPROP 2 LAST BOM_COST ST_SATA
J 0
(-3400 1625);
DISPLAY 1.361702 (-3400 1625);
PAINT ORANGE (-3400 1625);
DISPLAY INVISIBLE (-3400 1625);
FORCEPROP 2 LAST CDS_LIB mstr_symbols
J 0
(-3275 1800);
PAINT ORANGE (-3275 1800);
DISPLAY INVISIBLE (-3275 1800);
FORCEPROP 1 LAST COMMENT_BODY TRUE
J 0
(-3250 1900);
DISPLAY 1.319149 (-3250 1900);
PAINT ORANGE (-3250 1900);
DISPLAY INVISIBLE (-3250 1900);
FORCEADD DESIGN_NOTE..1
(-3275 850);
FORCEPROP 0 LAST L1 PLACE ON THE SECONDARY SIDE
J 0
(-3750 725);
DISPLAY 0.829787 (-3750 725);
PAINT WHITE (-3750 725);
FORCEPROP 0 LAST L2 POPULATE FOR 2-SIDED BOARD
J 0
(-3750 675);
DISPLAY 0.808511 (-3750 675);
PAINT ORANGE (-3750 675);
FORCEPROP 2 LAST ROOM ST_SATA
J 0
(-3400 675);
DISPLAY 1.361702 (-3400 675);
PAINT ORANGE (-3400 675);
DISPLAY INVISIBLE (-3400 675);
FORCEPROP 2 LAST BOM_COST ST_SATA
J 0
(-3400 675);
DISPLAY 1.361702 (-3400 675);
PAINT ORANGE (-3400 675);
DISPLAY INVISIBLE (-3400 675);
FORCEPROP 2 LAST CDS_LIB mstr_symbols
J 0
(-3275 850);
PAINT ORANGE (-3275 850);
DISPLAY INVISIBLE (-3275 850);
FORCEPROP 1 LAST COMMENT_BODY TRUE
J 0
(-3250 950);
DISPLAY 1.319149 (-3250 950);
PAINT ORANGE (-3250 950);
DISPLAY INVISIBLE (-3250 950);
WIRE 16 -1 (-650 100)(-650 150);
WIRE 16 -1 (1375 500)(1375 450);
WIRE 16 -1 (1125 450)(1375 450);
WIRE 16 -1 (-1050 100)(-1050 150);
WIRE 16 -1 (700 700)(700 650);
WIRE 16 -1 (700 650)(400 650);
WIRE 16 -1 (-1850 1600)(-1850 1550);
WIRE 16 -1 (-2050 1600)(-1850 1600);
WIRE 16 -1 (-1850 2500)(-1850 2550);
WIRE 16 -1 (-1950 2550)(-1850 2550);
WIRE 16 -1 (-1950 2500)(-1950 2550);
WIRE 16 -1 (-1950 2500)(-1950 2400);
WIRE 16 -1 (-2050 2500)(-1950 2500);
WIRE 16 -1 (-1950 2400)(-2050 2400);
WIRE 16 -1 (-2050 2200)(-1850 2200);
WIRE 16 -1 (-2050 2050)(-1850 2050);
WIRE 16 -1 (-1850 1300)(-1850 1250);
WIRE 16 -1 (-1950 1300)(-1850 1300);
WIRE 16 -1 (-1950 1250)(-1950 1300);
WIRE 16 -1 (-1950 1250)(-1950 1150);
WIRE 16 -1 (-2050 1250)(-1950 1250);
WIRE 16 -1 (-1950 1150)(-2050 1150);
WIRE 16 -1 (-2050 950)(-1850 950);
WIRE 16 -1 (-2050 800)(-1850 800);
WIRE 16 -1 (-1850 350)(-1850 300);
WIRE 16 -1 (-2050 350)(-1850 350);
WIRE 16 -1 (-1950 550)(-1850 550);
WIRE 16 -1 (-1950 600)(-1950 550);
WIRE 16 -1 (-2050 550)(-1950 550);
WIRE 16 -1 (-2050 600)(-1950 600);
WIRE 16 -1 (-1950 1800)(-1850 1800);
WIRE 16 -1 (-1950 1850)(-1950 1800);
WIRE 16 -1 (-2050 1800)(-1950 1800);
WIRE 16 -1 (-2050 1850)(-1950 1850);
WIRE 16 -1 (-2050 700)(-1950 700);
WIRE 16 -1 (-1050 650)(-1050 350);
WIRE 16 -1 (-1050 650)(-50 650);
FORCEPROP 0 LAST VOLTAGE 5
J 0
(-375 700);
DISPLAY 1.021277 (-375 700);
PAINT SKYBLUE (-375 700);
DISPLAY INVISIBLE (-375 700);
FORCEPROP 2 LAST SIG_NAME P5V_HDD_SATA
J 0
(-510 660);
DISPLAY 0.617021 (-510 660);
PAINT ORANGE (-510 660);
FORCEPROP 2 LASTPROP $XRERR UNIQUE?
J 0
(-750 660);
DISPLAY 0.638298 (-750 660);
PAINT MONO (-750 660);
DISPLAY INVISIBLE (-750 660);
WIRE 16 -1 (-2050 650)(-1950 650);
WIRE 16 -1 (-1950 700)(-1950 650);
WIRE 16 -1 (-1950 650)(-1200 650);
WIRE 16 -1 (-1200 650)(-1050 650);
WIRE 16 -1 (-2050 1950)(-1950 1950);
WIRE 16 -1 (-1950 1900)(-2050 1900);
WIRE 16 -1 (-1950 1950)(-1950 1900);
WIRE 16 -1 (-1200 1900)(-1200 650);
WIRE 16 -1 (-1200 1900)(-1950 1900);
WIRE 16 -1 (-2050 1050)(-1400 1050);
WIRE 16 -1 (-2050 2300)(-1400 2300);
WIRE 16 -1 (-1400 2300)(-1400 1050);
WIRE 16 -1 (-100 2300)(-1400 2300);
FORCEPROP 2 LAST SIG_NAME SATA6G_S1_TX_C_DP
J 0
(-935 2310);
DISPLAY 0.617021 (-935 2310);
PAINT ORANGE (-935 2310);
FORCEPROP 2 LASTPROP $XRERR UNIQUE?
J 0
(-1175 2310);
DISPLAY 0.638298 (-1175 2310);
PAINT MONO (-1175 2310);
DISPLAY INVISIBLE (-1175 2310);
WIRE 16 -1 (-2050 1000)(-1350 1000);
WIRE 16 -1 (-2050 2250)(-1350 2250);
WIRE 16 -1 (-1350 2250)(-1350 1000);
WIRE 16 -1 (650 2250)(-1350 2250);
FORCEPROP 2 LAST SIG_NAME SATA6G_S1_TX_C_DN
J 0
(-935 2260);
DISPLAY 0.617021 (-935 2260);
PAINT ORANGE (-935 2260);
FORCEPROP 2 LASTPROP $XRERR UNIQUE?
J 0
(-1175 2260);
DISPLAY 0.638298 (-1175 2260);
PAINT MONO (-1175 2260);
DISPLAY INVISIBLE (-1175 2260);
WIRE 16 -1 (-2050 900)(-1300 900);
WIRE 16 -1 (-2050 2150)(-1300 2150);
WIRE 16 -1 (-1300 2150)(-1300 900);
WIRE 16 -1 (250 2150)(-1300 2150);
FORCEPROP 2 LAST SIG_NAME SATA6G_S1_RX_C_DN
J 0
(-935 2160);
DISPLAY 0.617021 (-935 2160);
PAINT ORANGE (-935 2160);
FORCEPROP 2 LASTPROP $XRERR UNIQUE?
J 0
(-1175 2160);
DISPLAY 0.638298 (-1175 2160);
PAINT MONO (-1175 2160);
DISPLAY INVISIBLE (-1175 2160);
WIRE 3 2175 (-2600 50)(-1600 50);
WIRE 3 2175 (-1600 50)(-1600 2700);
WIRE 3 2175 (-2600 50)(-2600 2700);
WIRE 3 2175 (-2600 2700)(-1600 2700);
WIRE 16 -1 (-2050 1750)(-1950 1750);
WIRE 16 -1 (-2050 500)(-1950 500);
WIRE 16 -1 (-2050 1700)(-1950 1700);
WIRE 16 -1 (-1950 1750)(-1950 1700);
WIRE 16 -1 (-1950 1700)(-1150 1700);
WIRE 16 -1 (-2050 450)(-1950 450);
WIRE 16 -1 (-1950 500)(-1950 450);
WIRE 16 -1 (-650 350)(-650 450);
WIRE 16 -1 (-650 450)(825 450);
FORCEPROP 0 LAST VOLTAGE 12
J 0
(-375 525);
DISPLAY 1.021277 (-375 525);
PAINT SKYBLUE (-375 525);
DISPLAY INVISIBLE (-375 525);
FORCEPROP 2 LAST SIG_NAME P12V_HDD_SATA
J 0
(-510 460);
DISPLAY 0.617021 (-510 460);
PAINT ORANGE (-510 460);
FORCEPROP 2 LASTPROP $XRERR UNIQUE?
J 0
(-750 460);
DISPLAY 0.638298 (-750 460);
PAINT MONO (-750 460);
DISPLAY INVISIBLE (-750 460);
WIRE 16 -1 (-1950 450)(-1150 450);
WIRE 16 -1 (-1150 1700)(-1150 450);
WIRE 16 -1 (-1150 450)(-650 450);
WIRE 16 -1 (-2050 850)(-1250 850);
WIRE 16 -1 (-2050 2100)(-1250 2100);
WIRE 16 -1 (-1250 2100)(-1250 850);
WIRE 16 -1 (1125 2100)(-1250 2100);
FORCEPROP 2 LAST SIG_NAME SATA6G_S1_RX_C_DP
J 0
(-935 2110);
DISPLAY 0.617021 (-935 2110);
PAINT ORANGE (-935 2110);
FORCEPROP 2 LASTPROP $XRERR UNIQUE?
J 0
(-1175 2110);
DISPLAY 0.638298 (-1175 2110);
PAINT MONO (-1175 2110);
DISPLAY INVISIBLE (-1175 2110);
WIRE 16 -1 (1325 2100)(2075 2100);
FORCEPROP 2 LAST SIG_NAME SATA6G_S1_RX_DP
J 0
(1640 2110);
DISPLAY 0.617021 (1640 2110);
PAINT ORANGE (1640 2110);
WIRE 3 273 (525 550)(525 850);
WIRE 3 273 (525 550)(0 550);
WIRE 3 273 (0 850)(525 850);
WIRE 3 273 (0 850)(0 550);
WIRE 3 -1 (1300 -1150)(2625 -1150);
WIRE 3 -1 (1300 -1275)(2625 -1275);
WIRE 3 -1 (1300 -1350)(2625 -1350);
WIRE 3 -1 (1300 -1400)(2625 -1400);
WIRE 3 -1 (1300 -1475)(2625 -1475);
WIRE 16 -1 (450 2150)(2075 2150);
FORCEPROP 2 LAST SIG_NAME SATA6G_S1_RX_DN
J 0
(1640 2160);
DISPLAY 0.617021 (1640 2160);
PAINT ORANGE (1640 2160);
WIRE 16 -1 (850 2250)(2075 2250);
FORCEPROP 2 LAST SIG_NAME SATA6G_S1_TX_DN
J 0
(1640 2260);
DISPLAY 0.617021 (1640 2260);
PAINT ORANGE (1640 2260);
WIRE 16 -1 (100 2300)(2075 2300);
FORCEPROP 2 LAST SIG_NAME SATA6G_S1_TX_DP
J 0
(1640 2310);
DISPLAY 0.617021 (1640 2310);
PAINT ORANGE (1640 2310);
DOT 1 (-1950 550);
DOT 1 (-1950 650);
DOT 1 (-1950 1800);
DOT 1 (-1350 2250);
DOT 1 (-1950 1700);
DOT 1 (-1950 450);
DOT 1 (-1150 450);
DOT 1 (-650 450);
DOT 1 (-1950 1900);
DOT 1 (-1400 2300);
DOT 1 (-1250 2100);
DOT 1 (-1300 2150);
DOT 1 (-1950 2500);
DOT 1 (-1950 1250);
DOT 1 (-1050 650);
DOT 1 (-1200 650);
FORCENOTE
TP FAB1 CHANGE FUSE FOR FOLLOW LEOPARD DESIGN 0128
(-525 950) 0;
DISPLAY LEFT (-525 950);
DISPLAY 1.021277 (-525 950);
PAINT RED (-525 950);
FORCENOTE
CHANGE TO 5V
(2700 -1175) 0;
DISPLAY LEFT (2700 -1175);
DISPLAY 1.021277 (2700 -1175);
PAINT RED (2700 -1175);
FORCENOTE
TP FAB1 CHANGE TO SATA 13 PIN CONNECTORS 0104
(-2575 -50) 0;
DISPLAY LEFT (-2575 -50);
DISPLAY 1.021277 (-2575 -50);
PAINT RED (-2575 -50);
FORCENOTE
CHANGE TO GND
(2700 -1350) 0;
DISPLAY LEFT (2700 -1350);
DISPLAY 1.021277 (2700 -1350);
PAINT RED (2700 -1350);
FORCENOTE
CHANGE TO 12V
(2700 -1425) 0;
DISPLAY LEFT (2700 -1425);
DISPLAY 1.021277 (2700 -1425);
PAINT RED (2700 -1425);
FORCENOTE
CHANGE TO 12V
(2700 -1500) 0;
DISPLAY LEFT (2700 -1500);
DISPLAY 1.021277 (2700 -1500);
PAINT RED (2700 -1500);
FORCENOTE
ROOM=ST_SATA
(-4440 -1908) 0;
DISPLAY LEFT (-4440 -1908);
DISPLAY 0.617021 (-4440 -1908);
PAINT PURPLE (-4440 -1908);
FORCENOTE
TP FAB1 CHANGE PN TO 022.10014.0121 0121
(-2575 -125) 0;
DISPLAY LEFT (-2575 -125);
DISPLAY 1.021277 (-2575 -125);
PAINT RED (-2575 -125);
FORCENOTE
2.6A, 16V, POLY
(825 725) 0;
DISPLAY LEFT (825 725);
DISPLAY 0.617021 (825 725);
PAINT PURPLE (825 725);
FORCENOTE
CHANGE TO GND
(2700 -1300) 0;
DISPLAY LEFT (2700 -1300);
DISPLAY 1.021277 (2700 -1300);
PAINT RED (2700 -1300);
FORCENOTE
$CDS_IMAGE|圖片 9.jpg|1500|463
(1800 -875) 0;
DISPLAY LEFT (1800 -875);
FORCENOTE
$CDS_IMAGE|圖片 7.jpg|1410|500
(100 -900) 0;
DISPLAY LEFT (100 -900);
FORCENOTE
$CDS_IMAGE|圖片 10.jpg|1500|397
(1800 -1300) 0;
DISPLAY LEFT (1800 -1300);
FORCENOTE
$CDS_IMAGE|圖片 4.jpg|1747|500
(-1575 -900) 0;
DISPLAY LEFT (-1575 -900);
QUIT
